(kicad_pcb
	(version 20241229)
	(generator "pcbnew")
	(generator_version "9.0")
	(general
		(thickness 1.552)
		(legacy_teardrops no)
	)
	(paper "A4")
	(title_block
		(date "2023-07-25")
		(rev "1.1.4")
		(comment 9 "footprints 228-233 of 379")
	)
	(layers
		(0 "F.Cu" signal)
		(4 "In1.Cu" signal)
		(6 "In2.Cu" signal)
		(8 "In3.Cu" signal)
		(10 "In4.Cu" signal)
		(12 "In5.Cu" signal)
		(14 "In6.Cu" signal)
		(2 "B.Cu" signal)
		(9 "F.Adhes" user "F.Adhesive")
		(11 "B.Adhes" user "B.Adhesive")
		(13 "F.Paste" user)
		(15 "B.Paste" user)
		(5 "F.SilkS" user "F.Silkscreen")
		(7 "B.SilkS" user "B.Silkscreen")
		(1 "F.Mask" user)
		(3 "B.Mask" user)
		(17 "Dwgs.User" user "User.Drawings")
		(19 "Cmts.User" user "User.Comments")
		(21 "Eco1.User" user "User.Eco1")
		(23 "Eco2.User" user "User.Eco2")
		(25 "Edge.Cuts" user)
		(27 "Margin" user)
		(31 "F.CrtYd" user "F.Courtyard")
		(29 "B.CrtYd" user "B.Courtyard")
		(35 "F.Fab" user)
		(33 "B.Fab" user)
	)
	(footprint "antmicro-footprints:TP_SMD_0.75mm"
		(layer "F.Cu")
		(at 166.99 79.4)
		(property "Reference" "TP45"
			(at -1.36 -0.6 0)
			(layer "F.SilkS")
			(effects
				(font
					(size 0.65 0.65)
					(thickness 0.15)
				)
				(justify left bottom)
			)
		)
		(property "Value" "TP_0.75mm_SMD"
			(at 0 1.2 0)
			(layer "F.Fab")
			(hide yes)
			(effects
				(font
					(size 0.7 0.7)
					(thickness 0.15)
				)
				(justify left bottom)
			)
		)
		(property "Description" "SMT test point"
			(at 0 0 0)
			(layer "F.Fab")
			(hide yes)
			(effects
				(font
					(size 1.27 1.27)
					(thickness 0.15)
				)
			)
		)
		(property "Author" "Antmicro"
			(at 0 0 0)
			(layer "F.Fab")
			(hide yes)
			(effects
				(font
					(size 1 1)
					(thickness 0.15)
				)
			)
		)
		(property "License" "Apache-2.0"
			(at 0 0 0)
			(layer "F.Fab")
			(hide yes)
			(effects
				(font
					(size 1 1)
					(thickness 0.15)
				)
			)
		)
		(property "MPN" ""
			(at 0 0 0)
			(layer "F.Fab")
			(hide yes)
			(effects
				(font
					(size 1 1)
					(thickness 0.15)
				)
			)
		)
		(property "Manufacturer" ""
			(at 0 0 0)
			(layer "F.Fab")
			(hide yes)
			(effects
				(font
					(size 1 1)
					(thickness 0.15)
				)
			)
		)
		(sheetname "/Peripherals/")
		(sheetfile "peripherals.kicad_sch")
		(attr exclude_from_pos_files)
		(fp_circle
			(center 0 0)
			(end 0.475 0)
			(stroke
				(width 0.05)
				(type default)
			)
			(fill no)
			(layer "F.CrtYd")
		)
		(fp_text user "Author: Antmicro"
			(at -0.4 3.901 0)
			(layer "F.Fab")
			(effects
				(font
					(size 0.7 0.7)
					(thickness 0.15)
				)
				(justify left bottom)
			)
		)
		(fp_text user "${REFERENCE}"
			(at -0.4 2.7 0)
			(layer "F.Fab")
			(effects
				(font
					(size 0.7 0.7)
					(thickness 0.15)
				)
				(justify left bottom)
			)
		)
		(fp_text user "License: Apache-2.0"
			(at -0.4 5.101 0)
			(layer "F.Fab")
			(effects
				(font
					(size 0.7 0.7)
					(thickness 0.15)
				)
				(justify left bottom)
			)
		)
		(pad "1" smd circle
			(at 0 0)
			(size 0.75 0.75)
			(layers "F.Cu" "F.Mask")
			(net 314 "/Peripherals/QW_FLT")
			(pinfunction "1")
			(pintype "passive")
		)
	)
	(footprint "antmicro-footprints:R_0402_1005Metric"
		(layer "F.Cu")
		(at 101.94 115.185 90)
		(descr "Resistor SMD 0402")
		(tags "resistor SMD 0402")
		(property "Reference" "R95"
			(at 0.895 0.39 90)
			(layer "F.SilkS")
			(effects
				(font
					(size 0.65 0.65)
					(thickness 0.15)
				)
				(justify left bottom)
			)
		)
		(property "Value" "R_0R_0402"
			(at 0 1.4 90)
			(layer "F.Fab")
			(hide yes)
			(effects
				(font
					(size 0.7 0.7)
					(thickness 0.15)
				)
				(justify left bottom)
			)
		)
		(property "Datasheet" "https://industrial.panasonic.com/cdbs/www-data/pdf/RDA0000/AOA0000C301.pdf"
			(at 0 0 90)
			(layer "F.Fab")
			(hide yes)
			(effects
				(font
					(size 1.27 1.27)
					(thickness 0.15)
				)
			)
		)
		(property "Description" "SMD Chip Resistor, Jumper, 0 ohm, 100 mW, 0402 [1005 Metric], Thick Film, General Purpose"
			(at 0 0 90)
			(layer "F.Fab")
			(hide yes)
			(effects
				(font
					(size 1.27 1.27)
					(thickness 0.15)
				)
			)
		)
		(property "Author" "Antmicro"
			(at 217.125 13.245 0)
			(layer "F.Fab")
			(hide yes)
			(effects
				(font
					(size 1 1)
					(thickness 0.15)
				)
			)
		)
		(property "Current" "1A"
			(at 217.125 13.245 0)
			(layer "F.Fab")
			(hide yes)
			(effects
				(font
					(size 1 1)
					(thickness 0.15)
				)
			)
		)
		(property "License" "Apache-2.0"
			(at 217.125 13.245 0)
			(layer "F.Fab")
			(hide yes)
			(effects
				(font
					(size 1 1)
					(thickness 0.15)
				)
			)
		)
		(property "MPN" "ERJ2GE0R00X"
			(at 217.125 13.245 0)
			(layer "F.Fab")
			(hide yes)
			(effects
				(font
					(size 1 1)
					(thickness 0.15)
				)
			)
		)
		(property "Manufacturer" "Panasonic"
			(at 217.125 13.245 0)
			(layer "F.Fab")
			(hide yes)
			(effects
				(font
					(size 1 1)
					(thickness 0.15)
				)
			)
		)
		(property "Tolerance" "~"
			(at 217.125 13.245 0)
			(layer "F.Fab")
			(hide yes)
			(effects
				(font
					(size 1 1)
					(thickness 0.15)
				)
			)
		)
		(property "Val" "0R"
			(at 217.125 13.245 0)
			(layer "F.Fab")
			(hide yes)
			(effects
				(font
					(size 1 1)
					(thickness 0.15)
				)
			)
		)
		(sheetname "/FPGA/")
		(sheetfile "fpga.kicad_sch")
		(attr smd)
		(fp_rect
			(start -0.925 -0.47)
			(end 0.925 0.47)
			(stroke
				(width 0.05)
				(type default)
			)
			(fill no)
			(layer "F.CrtYd")
		)
		(fp_rect
			(start -0.5 -0.25)
			(end 0.5 0.25)
			(stroke
				(width 0.15)
				(type solid)
			)
			(fill no)
			(layer "F.Fab")
		)
		(fp_text user "License: Apache-2.0"
			(at -0.95 5.169 90)
			(layer "F.Fab")
			(effects
				(font
					(size 0.7 0.7)
					(thickness 0.15)
				)
				(justify left bottom)
			)
		)
		(fp_text user "${REFERENCE}"
			(at -0.95 3.168 90)
			(layer "F.Fab")
			(effects
				(font
					(size 0.7 0.7)
					(thickness 0.15)
				)
				(justify left bottom)
			)
		)
		(fp_text user "Author: Antmicro"
			(at -0.95 4.169 90)
			(layer "F.Fab")
			(effects
				(font
					(size 0.7 0.7)
					(thickness 0.15)
				)
				(justify left bottom)
			)
		)
		(pad "1" smd roundrect
			(at -0.48 0 90)
			(size 0.59 0.64)
			(layers "F.Cu" "F.Mask" "F.Paste")
			(roundrect_rratio 0.25)
			(net 138 "Net-(J7-Pad8)")
			(pintype "passive")
		)
		(pad "2" smd roundrect
			(at 0.48 0 90)
			(size 0.59 0.64)
			(layers "F.Cu" "F.Mask" "F.Paste")
			(roundrect_rratio 0.25)
			(net 172 "TDI")
			(pintype "passive")
		)
	)
	(footprint "antmicro-footprints:R_0402_1005Metric"
		(layer "F.Cu")
		(at 93 69.315 -90)
		(descr "Resistor SMD 0402")
		(tags "resistor SMD 0402")
		(property "Reference" "R56"
			(at -1.425 -0.28 270)
			(layer "F.SilkS")
			(effects
				(font
					(size 0.65 0.65)
					(thickness 0.15)
				)
				(justify left bottom)
			)
		)
		(property "Value" "R_105R_0402"
			(at 0 1.4 270)
			(layer "F.Fab")
			(hide yes)
			(effects
				(font
					(size 0.7 0.7)
					(thickness 0.15)
				)
				(justify left bottom)
			)
		)
		(property "Datasheet" "https://www.bourns.com/docs/product-datasheets/cr.pdf"
			(at 0 0 270)
			(layer "F.Fab")
			(hide yes)
			(effects
				(font
					(size 1.27 1.27)
					(thickness 0.15)
				)
			)
		)
		(property "Description" "SMD Chip Resistor, 105 ohm, ± 1%, 62.5 mW, 0402 [1005 Metric], Thick Film, General Purpose"
			(at 0 0 270)
			(layer "F.Fab")
			(hide yes)
			(effects
				(font
					(size 1.27 1.27)
					(thickness 0.15)
				)
			)
		)
		(property "Author" "Antmicro"
			(at 23.685 162.315 0)
			(layer "F.Fab")
			(hide yes)
			(effects
				(font
					(size 1 1)
					(thickness 0.15)
				)
			)
		)
		(property "License" "Apache-2.0"
			(at 23.685 162.315 0)
			(layer "F.Fab")
			(hide yes)
			(effects
				(font
					(size 1 1)
					(thickness 0.15)
				)
			)
		)
		(property "MPN" "CR0402-FX-1050GLF"
			(at 23.685 162.315 0)
			(layer "F.Fab")
			(hide yes)
			(effects
				(font
					(size 1 1)
					(thickness 0.15)
				)
			)
		)
		(property "Manufacturer" "Bourns"
			(at 23.685 162.315 0)
			(layer "F.Fab")
			(hide yes)
			(effects
				(font
					(size 1 1)
					(thickness 0.15)
				)
			)
		)
		(property "Tolerance" "1%"
			(at 23.685 162.315 0)
			(layer "F.Fab")
			(hide yes)
			(effects
				(font
					(size 1 1)
					(thickness 0.15)
				)
			)
		)
		(property "Val" "105R"
			(at 23.685 162.315 0)
			(layer "F.Fab")
			(hide yes)
			(effects
				(font
					(size 1 1)
					(thickness 0.15)
				)
			)
		)
		(sheetname "/SDI/")
		(sheetfile "sdi.kicad_sch")
		(attr smd)
		(fp_rect
			(start -0.925 -0.47)
			(end 0.925 0.47)
			(stroke
				(width 0.05)
				(type default)
			)
			(fill no)
			(layer "F.CrtYd")
		)
		(fp_rect
			(start -0.5 -0.25)
			(end 0.5 0.25)
			(stroke
				(width 0.15)
				(type solid)
			)
			(fill no)
			(layer "F.Fab")
		)
		(fp_text user "${REFERENCE}"
			(at -0.95 3.168 270)
			(layer "F.Fab")
			(effects
				(font
					(size 0.7 0.7)
					(thickness 0.15)
				)
				(justify left bottom)
			)
		)
		(fp_text user "License: Apache-2.0"
			(at -0.95 5.169 270)
			(layer "F.Fab")
			(effects
				(font
					(size 0.7 0.7)
					(thickness 0.15)
				)
				(justify left bottom)
			)
		)
		(fp_text user "Author: Antmicro"
			(at -0.95 4.169 270)
			(layer "F.Fab")
			(effects
				(font
					(size 0.7 0.7)
					(thickness 0.15)
				)
				(justify left bottom)
			)
		)
		(pad "1" smd roundrect
			(at -0.48 0 270)
			(size 0.59 0.64)
			(layers "F.Cu" "F.Mask" "F.Paste")
			(roundrect_rratio 0.25)
			(net 3 "+1V2")
			(pintype "passive")
		)
		(pad "2" smd roundrect
			(at 0.48 0 270)
			(size 0.59 0.64)
			(layers "F.Cu" "F.Mask" "F.Paste")
			(roundrect_rratio 0.25)
			(net 244 "Net-(U15C-VCO_{VDD})")
			(pintype "passive")
		)
	)
	(footprint "antmicro-footprints:LED_0603_1608Metric_G"
		(layer "F.Cu")
		(at 172.63 80.968952 180)
		(descr "LED SMD 0603 Green")
		(tags "LED SMD 0603 Green")
		(property "Reference" "D9"
			(at -1.4 0.71 90)
			(layer "F.SilkS")
			(effects
				(font
					(size 0.65 0.65)
					(thickness 0.15)
				)
				(justify right top)
			)
		)
		(property "Value" "LED_G_0603_LTST-C190GKT"
			(at 0 1.6 0)
			(layer "F.Fab")
			(hide yes)
			(effects
				(font
					(size 0.7 0.7)
					(thickness 0.15)
				)
				(justify right top)
			)
		)
		(property "Datasheet" "https://media.digikey.com/pdf/Data%20Sheets/Lite-On%20PDFs/LTST-C190GKT.pdf"
			(at 0 0 0)
			(layer "F.Fab")
			(hide yes)
			(effects
				(font
					(size 1.27 1.27)
					(thickness 0.15)
				)
			)
		)
		(property "Description" "LED, Green, SMD, 0603, 20 mA, 2.1 V, 569 nm"
			(at 0 0 0)
			(layer "F.Fab")
			(hide yes)
			(effects
				(font
					(size 1.27 1.27)
					(thickness 0.15)
				)
			)
		)
		(property "Author" "Antmicro"
			(at 0 0 0)
			(layer "F.Fab")
			(hide yes)
			(effects
				(font
					(size 1 1)
					(thickness 0.15)
				)
			)
		)
		(property "License" "Apache-2.0"
			(at 0 0 0)
			(layer "F.Fab")
			(hide yes)
			(effects
				(font
					(size 1 1)
					(thickness 0.15)
				)
			)
		)
		(property "MPN" "LTST-C190GKT"
			(at 0 0 0)
			(layer "F.Fab")
			(hide yes)
			(effects
				(font
					(size 1 1)
					(thickness 0.15)
				)
			)
		)
		(property "Manufacturer" "Lite-On"
			(at 0 0 0)
			(layer "F.Fab")
			(hide yes)
			(effects
				(font
					(size 1 1)
					(thickness 0.15)
				)
			)
		)
		(property "Color" "Green"
			(at 0 0 180)
			(unlocked yes)
			(layer "F.Fab")
			(hide yes)
			(effects
				(font
					(size 1 1)
					(thickness 0.15)
				)
			)
		)
		(sheetname "/Peripherals/")
		(sheetfile "peripherals.kicad_sch")
		(attr smd)
		(fp_line
			(start 0.22 0.35)
			(end -0.22 0.35)
			(stroke
				(width 0.15)
				(type solid)
			)
			(layer "F.SilkS")
		)
		(fp_line
			(start 0.22 -0.35)
			(end -0.22 -0.35)
			(stroke
				(width 0.15)
				(type solid)
			)
			(layer "F.SilkS")
		)
		(fp_line
			(start 0.105328 0.201008)
			(end 0.105328 -0.198992)
			(stroke
				(width 0.1)
				(type solid)
			)
			(layer "F.SilkS")
		)
		(fp_line
			(start 0.105328 0.201008)
			(end -0.094672 0.001008)
			(stroke
				(width 0.1)
				(type solid)
			)
			(layer "F.SilkS")
		)
		(fp_line
			(start 0.105328 0.001008)
			(end 0.24 0.001)
			(stroke
				(width 0.1)
				(type solid)
			)
			(layer "F.SilkS")
		)
		(fp_line
			(start -0.094672 0.201008)
			(end -0.094672 -0.198992)
			(stroke
				(width 0.1)
				(type solid)
			)
			(layer "F.SilkS")
		)
		(fp_line
			(start -0.094672 0.001008)
			(end 0.105328 -0.198992)
			(stroke
				(width 0.1)
				(type solid)
			)
			(layer "F.SilkS")
		)
		(fp_line
			(start -0.094672 0.001008)
			(end -0.24 0.001008)
			(stroke
				(width 0.1)
				(type solid)
			)
			(layer "F.SilkS")
		)
		(fp_line
			(start -1.18 -0.319)
			(end -1.18 0.321)
			(stroke
				(width 0.15)
				(type solid)
			)
			(layer "F.SilkS")
		)
		(fp_rect
			(start 1.25 0.65)
			(end -1.25 -0.65)
			(stroke
				(width 0.05)
				(type solid)
			)
			(fill no)
			(layer "F.CrtYd")
		)
		(fp_line
			(start 0.599 0)
			(end 0.201 0)
			(stroke
				(width 0.15)
				(type solid)
			)
			(layer "F.Fab")
		)
		(fp_line
			(start 0.201 0.2)
			(end 0.201 0)
			(stroke
				(width 0.15)
				(type solid)
			)
			(layer "F.Fab")
		)
		(fp_line
			(start 0.201 0)
			(end 0.201 -0.202)
			(stroke
				(width 0.15)
				(type solid)
			)
			(layer "F.Fab")
		)
		(fp_line
			(start 0.201 -0.202)
			(end -0.101 0)
			(stroke
				(width 0.15)
				(type solid)
			)
			(layer "F.Fab")
		)
		(fp_line
			(start -0.101 0)
			(end 0.201 0.2)
			(stroke
				(width 0.15)
				(type solid)
			)
			(layer "F.Fab")
		)
		(fp_line
			(start -0.199 0.2)
			(end -0.199 0.1)
			(stroke
				(width 0.15)
				(type solid)
			)
			(layer "F.Fab")
		)
		(fp_line
			(start -0.199 0)
			(end -0.597 0)
			(stroke
				(width 0.15)
				(type solid)
			)
			(layer "F.Fab")
		)
		(fp_line
			(start -0.199 -0.202)
			(end -0.199 0.1)
			(stroke
				(width 0.15)
				(type solid)
			)
			(layer "F.Fab")
		)
		(fp_rect
			(start 0.848 0.4)
			(end -0.85 -0.402)
			(stroke
				(width 0.15)
				(type solid)
			)
			(fill no)
			(layer "F.Fab")
		)
		(fp_text user "Author: Antmicro"
			(at -1.4224 4.799 0)
			(layer "F.Fab")
			(effects
				(font
					(size 0.7 0.7)
					(thickness 0.15)
				)
				(justify right top)
			)
		)
		(fp_text user "${REFERENCE}"
			(at -1.4224 5.999 0)
			(layer "F.Fab")
			(effects
				(font
					(size 0.7 0.7)
					(thickness 0.15)
				)
				(justify right top)
			)
		)
		(fp_text user "License: Apache-2.0"
			(at -1.4224 3.599 0)
			(layer "F.Fab")
			(effects
				(font
					(size 0.7 0.7)
					(thickness 0.15)
				)
				(justify right top)
			)
		)
		(pad "1" smd roundrect
			(at -0.7 0)
			(size 0.8 1)
			(layers "F.Cu" "F.Mask" "F.Paste")
			(roundrect_rratio 0.2)
			(net 1 "GND")
			(pinfunction "C")
			(pintype "passive")
		)
		(pad "2" smd roundrect
			(at 0.7 0)
			(size 0.8 1)
			(layers "F.Cu" "F.Mask" "F.Paste")
			(roundrect_rratio 0.2)
			(net 255 "Net-(D9-A)")
			(pinfunction "A")
			(pintype "passive")
		)
	)
	(footprint "antmicro-footprints:TP_SMD_0.75mm"
		(layer "F.Cu")
		(at 96.18 84.37)
		(property "Reference" "TP13"
			(at -3.05 0.27 0)
			(layer "F.SilkS")
			(effects
				(font
					(size 0.65 0.65)
					(thickness 0.15)
				)
				(justify left bottom)
			)
		)
		(property "Value" "TP_0.75mm_SMD"
			(at 0 1.2 0)
			(layer "F.Fab")
			(hide yes)
			(effects
				(font
					(size 0.7 0.7)
					(thickness 0.15)
				)
				(justify left bottom)
			)
		)
		(property "Description" "SMT test point"
			(at 0 0 0)
			(layer "F.Fab")
			(hide yes)
			(effects
				(font
					(size 1.27 1.27)
					(thickness 0.15)
				)
			)
		)
		(property "Author" "Antmicro"
			(at 0 0 0)
			(layer "F.Fab")
			(hide yes)
			(effects
				(font
					(size 1 1)
					(thickness 0.15)
				)
			)
		)
		(property "License" "Apache-2.0"
			(at 0 0 0)
			(layer "F.Fab")
			(hide yes)
			(effects
				(font
					(size 1 1)
					(thickness 0.15)
				)
			)
		)
		(property "MPN" ""
			(at 0 0 0)
			(layer "F.Fab")
			(hide yes)
			(effects
				(font
					(size 1 1)
					(thickness 0.15)
				)
			)
		)
		(property "Manufacturer" ""
			(at 0 0 0)
			(layer "F.Fab")
			(hide yes)
			(effects
				(font
					(size 1 1)
					(thickness 0.15)
				)
			)
		)
		(sheetname "/SDI/")
		(sheetfile "sdi.kicad_sch")
		(attr exclude_from_pos_files)
		(fp_circle
			(center 0 0)
			(end 0.475 0)
			(stroke
				(width 0.05)
				(type default)
			)
			(fill no)
			(layer "F.CrtYd")
		)
		(fp_text user "Author: Antmicro"
			(at -0.4 3.901 0)
			(layer "F.Fab")
			(effects
				(font
					(size 0.7 0.7)
					(thickness 0.15)
				)
				(justify left bottom)
			)
		)
		(fp_text user "${REFERENCE}"
			(at -0.4 2.7 0)
			(layer "F.Fab")
			(effects
				(font
					(size 0.7 0.7)
					(thickness 0.15)
				)
				(justify left bottom)
			)
		)
		(fp_text user "License: Apache-2.0"
			(at -0.4 5.101 0)
			(layer "F.Fab")
			(effects
				(font
					(size 0.7 0.7)
					(thickness 0.15)
				)
				(justify left bottom)
			)
		)
		(pad "1" smd circle
			(at 0 0)
			(size 0.75 0.75)
			(layers "F.Cu" "F.Mask")
			(net 377 "Net-(U15B-XTAL_OUT)")
			(pinfunction "1")
			(pintype "passive")
		)
	)
	(footprint "antmicro-footprints:R_0402_1005Metric"
		(layer "F.Cu")
		(at 110.63 105.55)
		(descr "Resistor SMD 0402")
		(tags "resistor SMD 0402")
		(property "Reference" "R79"
			(at 1 0.39 0)
			(layer "F.SilkS")
			(effects
				(font
					(size 0.65 0.65)
					(thickness 0.15)
				)
				(justify left bottom)
			)
		)
		(property "Value" "R_1k_0402"
			(at 0 1.4 0)
			(layer "F.Fab")
			(hide yes)
			(effects
				(font
					(size 0.7 0.7)
					(thickness 0.15)
				)
				(justify left bottom)
			)
		)
		(property "Datasheet" "https://www.bourns.com/docs/product-datasheets/cr.pdf"
			(at 0 0 0)
			(layer "F.Fab")
			(hide yes)
			(effects
				(font
					(size 1.27 1.27)
					(thickness 0.15)
				)
			)
		)
		(property "Description" "SMD Chip Resistor, 1 kohm, ± 1%, 63 mW, 0402 [1005 Metric], Thick Film, General Purpose"
			(at 0 0 0)
			(layer "F.Fab")
			(hide yes)
			(effects
				(font
					(size 1.27 1.27)
					(thickness 0.15)
				)
			)
		)
		(property "Author" "Antmicro"
			(at 0 0 0)
			(layer "F.Fab")
			(hide yes)
			(effects
				(font
					(size 1 1)
					(thickness 0.15)
				)
			)
		)
		(property "License" "Apache-2.0"
			(at 0 0 0)
			(layer "F.Fab")
			(hide yes)
			(effects
				(font
					(size 1 1)
					(thickness 0.15)
				)
			)
		)
		(property "MPN" "CR0402-FX-1001GLF"
			(at 0 0 0)
			(layer "F.Fab")
			(hide yes)
			(effects
				(font
					(size 1 1)
					(thickness 0.15)
				)
			)
		)
		(property "Manufacturer" "Bourns"
			(at 0 0 0)
			(layer "F.Fab")
			(hide yes)
			(effects
				(font
					(size 1 1)
					(thickness 0.15)
				)
			)
		)
		(property "Tolerance" "1%"
			(at 0 0 0)
			(layer "F.Fab")
			(hide yes)
			(effects
				(font
					(size 1 1)
					(thickness 0.15)
				)
			)
		)
		(property "Val" "1k"
			(at 0 0 0)
			(layer "F.Fab")
			(hide yes)
			(effects
				(font
					(size 1 1)
					(thickness 0.15)
				)
			)
		)
		(sheetname "/FPGA/")
		(sheetfile "fpga.kicad_sch")
		(attr smd)
		(fp_rect
			(start -0.925 -0.47)
			(end 0.925 0.47)
			(stroke
				(width 0.05)
				(type default)
			)
			(fill no)
			(layer "F.CrtYd")
		)
		(fp_rect
			(start -0.5 -0.25)
			(end 0.5 0.25)
			(stroke
				(width 0.15)
				(type solid)
			)
			(fill no)
			(layer "F.Fab")
		)
		(fp_text user "${REFERENCE}"
			(at -0.95 3.168 0)
			(layer "F.Fab")
			(effects
				(font
					(size 0.7 0.7)
					(thickness 0.15)
				)
				(justify left bottom)
			)
		)
		(fp_text user "Author: Antmicro"
			(at -0.95 4.169 0)
			(layer "F.Fab")
			(effects
				(font
					(size 0.7 0.7)
					(thickness 0.15)
				)
				(justify left bottom)
			)
		)
		(fp_text user "License: Apache-2.0"
			(at -0.95 5.169 0)
			(layer "F.Fab")
			(effects
				(font
					(size 0.7 0.7)
					(thickness 0.15)
				)
				(justify left bottom)
			)
		)
		(pad "1" smd roundrect
			(at -0.48 0)
			(size 0.59 0.64)
			(layers "F.Cu" "F.Mask" "F.Paste")
			(roundrect_rratio 0.25)
			(net 309 "Net-(U17-~{INT})")
			(pintype "passive")
		)
		(pad "2" smd roundrect
			(at 0.48 0)
			(size 0.59 0.64)
			(layers "F.Cu" "F.Mask" "F.Paste")
			(roundrect_rratio 0.25)
			(net 2 "+3V3")
			(pintype "passive")
		)
	)
)
